# T6G (Grand Teton) — schematic parts with pin connectivity, parts 3331–3493 of 8303; source: Cadence DE-HDL packaged netlist (pstxprt.dat, pstxnet.dat, pstchip.dat)

PC560  Q_CAP  0.22UF 16V 10% X7R  pkg 0402  page 195 : 1 = SW_PVDDCR_CPU0_P0_BOOT3_RC ; 2 = SW_PVDDCR_CPU0_P0_PH3
PC561  Q_CAP  0.22UF 16V 10% X7R  pkg 0402  page 195 : 1 = SW_PVDDCR_CPU0_P0_BOOT4_RC ; 2 = SW_PVDDCR_CPU0_P0_PH4
PC562_3  Q_CAP  22UF 4V 20% X6S  pkg C0805  page 195 : 1 = PVDDCR_CPU0_P0 ; 2 = GND
PC563_4  Q_CAP  22UF 4V 20% X6S  pkg C0805  page 195 : 1 = PVDDCR_CPU0_P0 ; 2 = GND
PC564_3  Q_CAP  22UF 4V 20% X6S  pkg C0805  page 195 : 1 = PVDDCR_CPU0_P0 ; 2 = GND
PC565_4  Q_CAP  22UF 4V 20% X6S  pkg C0805  page 195 : 1 = PVDDCR_CPU0_P0 ; 2 = GND
PC566  Q_CAPP  270UF 16V 20% OSCON  pkg THLF  page 190 : 1 = SW_P3V3_AUX_FLT ; 2 = GND
PC566_5  Q_CAP  0.1UF 25V 10% X7R  pkg 0402  page 196 : 1 = PVDDCR_CPU0_P0_VCCS ; 2 = GND
PC567  Q_CAP  2.2UF 10V 10% X6S  pkg C0402  page 196 : 1 = PVDDCR_CPU0_P0_VCC5 ; 2 = GND
PC568  Q_CAP  0.22UF 25V 10% X7R  pkg C0402  page 190 : 1 = SW_P3V3_AUX_BOOTR ; 2 = SW_P3V3_AUX_BOOT_R
PC568_C0P0_5  Q_CAP  2.2UF 10V 10% X6S  pkg C0402  page 196 : 1 = PVDDCR_CPU0_P0_PVCC ; 2 = GND
PC569  Q_CAP  10PF 50V 1% NPO  pkg 0402  page 190 : 1 = P3V3_AUX_FB ; 2 = P3V3_AUX
PC569_5  Q_CAP  1UF 25V 10% X6S  pkg C0402  page 196 : 1 = SW_P12V_AUX_PVDDCR_CPU0_P0_FLT ; 2 = GND
PC570  Q_CAP  22UF 16V 20% X6S  pkg C0805  page 190 : 1 = SW_P3V3_AUX_FLT ; 2 = GND
PC570_5  Q_CAP  0.1UF 25V 10% X7R  pkg 0402  page 196 : 1 = SW_P12V_AUX_PVDDCR_CPU0_P0_FLT ; 2 = GND
PC571  Q_CAP  22UF 16V 20% X6S  pkg C0805  page 190 : 1 = SW_P3V3_AUX_FLT ; 2 = GND
PC571_5  Q_CAP  22UF 16V 20% X6S  pkg C0805  page 196 : 1 = SW_P12V_AUX_PVDDCR_CPU0_P0_FLT ; 2 = GND
PC572_5  Q_CAP  22UF 16V 20% X6S  pkg C0805  page 196 : 1 = SW_P12V_AUX_PVDDCR_CPU0_P0_FLT ; 2 = GND
PC573_5  Q_CAP  22UF 16V 20% X6S  pkg C0805  page 196 : 1 = SW_P12V_AUX_PVDDCR_CPU0_P0_FLT ; 2 = GND
PC574  Q_CAP  0.22UF 16V 10% X7R  pkg 0402  page 196 : 1 = SW_PVDDCR_CPU0_P0_BOOT5_RC ; 2 = SW_PVDDCR_CPU0_P0_PH5
PC575_5  Q_CAP  22UF 4V 20% X6S  pkg C0805  page 196 : 1 = PVDDCR_CPU0_P0 ; 2 = GND
PC576  Q_CAP  22UF 16V 20% X6S  pkg C0805  page 190 : 1 = SW_P3V3_AUX_FLT ; 2 = GND
PC576_5  Q_CAP  22UF 4V 20% X6S  pkg C0805  page 196 : 1 = PVDDCR_CPU0_P0 ; 2 = GND
PC577  Q_CAP  0.1UF 25V 10% X7R  pkg 0402  page 190 : 1 = SW_P3V3_AUX_FLT ; 2 = GND
PC577_7  Q_CAP  0.1UF 25V 10% X7R  pkg 0402  page 198 : 1 = PVDDCR_CPU0_P0_VCCS ; 2 = GND
PC578_8  Q_CAP  0.1UF 25V 10% X7R  pkg 0402  page 198 : 1 = PVDDCR_CPU0_P0_VCCS ; 2 = GND
PC579  Q_CAP  2.2UF 10V 10% X6S  pkg C0402  page 198 : 1 = PVDDCR_SOC_P0_VCC1 ; 2 = GND
PC580  Q_CAP  2.2UF 10V 10% X6S  pkg C0402  page 198 : 1 = PVDDCR_SOC_P0_VCC2 ; 2 = GND
PC581  Q_CAP  4.7UF 16V 10% X6S  pkg C0603  page 190 : 1 = P3V3_AUX_VDRV ; 2 = GND
PC581_SOP0_1  Q_CAP  2.2UF 10V 10% X6S  pkg C0402  page 198 : 1 = PVDDCR_CPU0_P0_PVCC ; 2 = GND
PC582_SOP0_2  Q_CAP  2.2UF 10V 10% X6S  pkg C0402  page 198 : 1 = PVDDCR_CPU0_P0_PVCC ; 2 = GND
PC583  Q_CAP  0.1UF 25V 10% X7R  pkg 0402  page 198 : 1 = P12V_AUX ; 2 = GND
PC583_1  Q_CAP  0.1UF 25V 10% X7R  pkg 0402  page 198 : 1 = SW_P12V_AUX_PVDDCR_SOC_P0_FLT ; 2 = GND
PC584_2  Q_CAP  1UF 25V 10% X6S  pkg C0402  page 198 : 1 = SW_P12V_AUX_PVDDCR_SOC_P0_FLT ; 2 = GND
PC585_1  Q_CAP  1UF 25V 10% X6S  pkg C0402  page 198 : 1 = SW_P12V_AUX_PVDDCR_SOC_P0_FLT ; 2 = GND
PC586_2  Q_CAP  0.1UF 25V 10% X7R  pkg 0402  page 198 : 1 = SW_P12V_AUX_PVDDCR_SOC_P0_FLT ; 2 = GND
PC587_1  Q_CAP  22UF 16V 20% X6S  pkg C0805  page 198 : 1 = SW_P12V_AUX_PVDDCR_SOC_P0_FLT ; 2 = GND
PC588_2  Q_CAP  22UF 16V 20% X6S  pkg C0805  page 198 : 1 = SW_P12V_AUX_PVDDCR_SOC_P0_FLT ; 2 = GND
PC589_1  Q_CAP  22UF 16V 20% X6S  pkg C0805  page 198 : 1 = SW_P12V_AUX_PVDDCR_SOC_P0_FLT ; 2 = GND
PC590_2  Q_CAP  22UF 16V 20% X6S  pkg C0805  page 198 : 1 = SW_P12V_AUX_PVDDCR_SOC_P0_FLT ; 2 = GND
PC591  Q_CAP  2.2UF 16V 10% X6S  pkg C0603  page 190 : 1 = P3V3_AUX_VCC ; 2 = GND
PC591_1  Q_CAP  22UF 16V 20% X6S  pkg C0805  page 198 : 1 = SW_P12V_AUX_PVDDCR_SOC_P0_FLT ; 2 = GND
PC592_2  Q_CAP  22UF 16V 20% X6S  pkg C0805  page 198 : 1 = SW_P12V_AUX_PVDDCR_SOC_P0_FLT ; 2 = GND
PC593  Q_CAP  0.22UF 16V 10% X7R  pkg 0402  page 198 : 1 = SW_PVDDCR_SOC_P0_BOOT1_RC ; 2 = SW_PVDDCR_SOC_P0_PH1
PC593_1  Q_CAP  22UF 16V 20% X6S  pkg C0805  page 198 : 1 = SW_P12V_AUX_PVDDCR_SOC_P0_FLT ; 2 = GND
PC594  Q_CAP  0.22UF 16V 10% X7R  pkg 0402  page 198 : 1 = SW_PVDDCR_SOC_P0_BOOT2_RC ; 2 = SW_PVDDCR_SOC_P0_PH2
PC595_2  Q_CAP  22UF 16V 20% X6S  pkg C0805  page 198 : 1 = SW_P12V_AUX_PVDDCR_SOC_P0_FLT ; 2 = GND
PC596  Q_CAPP  270UF 16V 20% OSCON  pkg THLF  page 198 : 1 = SW_P12V_AUX_PVDDCR_SOC_P0_FLT ; 2 = GND
PC597  Q_CAPP  470UF 2.5V 20% EMPTY  pkg SMLF  page 198 : 1 = PVDDCR_SOC_P0 ; 2 = GND
PC598  Q_CAPP  470UF 2.5V 20% SPCAP  pkg SMLF  page 198 : 1 = PVDDCR_SOC_P0 ; 2 = GND
PC599  Q_CAP  0.1UF 25V 10% X7R  pkg 0402  page 198 : 1 = PVDDCR_SOC_P0 ; 2 = GND
PC600_2  Q_CAP  22UF 4V 20% X6S  pkg C0805  page 198 : 1 = PVDDCR_SOC_P0 ; 2 = GND
PC601  Q_CAPP  470UF 2.5V 20% SPCAP  pkg SMLF  page 198 : 1 = PVDDCR_SOC_P0 ; 2 = GND
PC602_1  Q_CAP  22UF 4V 20% X6S  pkg C0805  page 198 : 1 = PVDDCR_SOC_P0 ; 2 = GND
PC603_2  Q_CAP  22UF 4V 20% X6S  pkg C0805  page 198 : 1 = PVDDCR_SOC_P0 ; 2 = GND
PC604_1  Q_CAP  22UF 4V 20% X6S  pkg C0805  page 198 : 1 = PVDDCR_SOC_P0 ; 2 = GND
PC605_9  Q_CAP  0.1UF 25V 10% X7R  pkg 0402  page 199 : 1 = PVDDCR_CPU0_P0_VCCS ; 2 = GND
PC606  Q_CAP  2.2UF 10V 10% X6S  pkg C0402  page 199 : 1 = PVDDCR_SOC_P0_VCC3 ; 2 = GND
PC607_SOP0_3  Q_CAP  2.2UF 10V 10% X6S  pkg C0402  page 199 : 1 = PVDDCR_CPU0_P0_PVCC ; 2 = GND
PC608_3  Q_CAP  1UF 25V 10% X6S  pkg C0402  page 199 : 1 = SW_P12V_AUX_PVDDCR_SOC_P0_FLT ; 2 = GND
PC609_3  Q_CAP  0.1UF 25V 10% X7R  pkg 0402  page 199 : 1 = SW_P12V_AUX_PVDDCR_SOC_P0_FLT ; 2 = GND
PC610_3  Q_CAP  22UF 16V 20% X6S  pkg C0805  page 199 : 1 = SW_P12V_AUX_PVDDCR_SOC_P0_FLT ; 2 = GND
PC611_3  Q_CAP  22UF 16V 20% X6S  pkg C0805  page 199 : 1 = SW_P12V_AUX_PVDDCR_SOC_P0_FLT ; 2 = GND
PC612  Q_CAP  0.22UF 16V 10% X7R  pkg 0402  page 199 : 1 = SW_PVDDCR_SOC_P0_BOOT3_RC ; 2 = SW_PVDDCR_SOC_P0_PH3
PC612_3  Q_CAP  22UF 16V 20% X6S  pkg C0805  page 199 : 1 = SW_P12V_AUX_PVDDCR_SOC_P0_FLT ; 2 = GND
PC613_3  Q_CAP  22UF 16V 20% X6S  pkg C0805  page 199 : 1 = SW_P12V_AUX_PVDDCR_SOC_P0_FLT ; 2 = GND
PC614_3  Q_CAP  22UF 4V 20% X6S  pkg C0805  page 199 : 1 = PVDDCR_SOC_P0 ; 2 = GND
PC615_3  Q_CAP  22UF 4V 20% X6S  pkg C0805  page 199 : 1 = PVDDCR_SOC_P0 ; 2 = GND
PC616  Q_CAP  2.2UF 10V 10% X6S  pkg C0402  page 223 : 1 = PVDDIO_P1_VCC4 ; 2 = GND
PC617  Q_CAP  2.2UF 10V 10% X6S  pkg C0402  page 223 : 1 = PVDDIO_P1_VCC3 ; 2 = GND
PC618_IOP1_4  Q_CAP  2.2UF 10V 10% X6S  pkg C0402  page 223 : 1 = PVDDCR_CPU1_P1_PVCC ; 2 = GND
PC619_IOP1_3  Q_CAP  2.2UF 10V 10% X6S  pkg C0402  page 223 : 1 = PVDDCR_CPU1_P1_PVCC ; 2 = GND
PC620_9  Q_CAP  0.1UF 25V 10% X7R  pkg 0402  page 223 : 1 = PVDDCR_CPU1_P1_VCCS ; 2 = GND
PC621_10  Q_CAP  0.1UF 25V 10% X7R  pkg 0402  page 223 : 1 = PVDDCR_CPU1_P1_VCCS ; 2 = GND
PC622_3  Q_CAP  0.1UF 25V 10% X7R  pkg 0402  page 223 : 1 = SW_P12V_AUX_PVDDIO_P1_FLT ; 2 = GND
PC623_4  Q_CAP  0.1UF 25V 10% X7R  pkg 0402  page 223 : 1 = SW_P12V_AUX_PVDDIO_P1_FLT ; 2 = GND
PC624_3  Q_CAP  1UF 25V 10% X6S  pkg C0402  page 223 : 1 = SW_P12V_AUX_PVDDIO_P1_FLT ; 2 = GND
PC625_4  Q_CAP  1UF 25V 10% X6S  pkg C0402  page 223 : 1 = SW_P12V_AUX_PVDDIO_P1_FLT ; 2 = GND
PC626_3  Q_CAP  22UF 16V 20% X6S  pkg C0805  page 223 : 1 = SW_P12V_AUX_PVDDIO_P1_FLT ; 2 = GND
PC627_4  Q_CAP  22UF 16V 20% X6S  pkg C0805  page 223 : 1 = SW_P12V_AUX_PVDDIO_P1_FLT ; 2 = GND
PC628_3  Q_CAP  22UF 16V 20% X6S  pkg C0805  page 223 : 1 = SW_P12V_AUX_PVDDIO_P1_FLT ; 2 = GND
PC629_4  Q_CAP  22UF 16V 20% X6S  pkg C0805  page 223 : 1 = SW_P12V_AUX_PVDDIO_P1_FLT ; 2 = GND
PC630  Q_CAP  0.22UF 16V 10% X7R  pkg 0402  page 223 : 1 = SW_PVDDIO_P1_BOOT4_R ; 2 = SW_PVDDIO_P1_BOOTR4
PC631  Q_CAP  0.22UF 16V 10% X7R  pkg 0402  page 223 : 1 = SW_PVDDIO_P1_BOOT3_R ; 2 = SW_PVDDIO_P1_BOOTR3
PC632_3  Q_CAP  22UF 16V 20% X6S  pkg C0805  page 223 : 1 = SW_P12V_AUX_PVDDIO_P1_FLT ; 2 = GND
PC633_4  Q_CAP  22UF 16V 20% X6S  pkg C0805  page 223 : 1 = SW_P12V_AUX_PVDDIO_P1_FLT ; 2 = GND
PC634_4  Q_CAP  22UF 4V 20% X6S  pkg C0805  page 223 : 1 = PVDDIO_P1 ; 2 = GND
PC635_3  Q_CAP  22UF 4V 20% X6S  pkg C0805  page 223 : 1 = PVDDIO_P1 ; 2 = GND
PC636_4  Q_CAP  22UF 4V 20% X6S  pkg C0805  page 223 : 1 = PVDDIO_P1 ; 2 = GND
PC637_3  Q_CAP  22UF 4V 20% X6S  pkg C0805  page 223 : 1 = PVDDIO_P1 ; 2 = GND
PC638  Q_CAP  0.1UF 25V 10% X7R  pkg 0402  page 224 : 1 = PVDD11_S3_P1_VMON ; 2 = GND
PC639  Q_CAP  3300PF 50V 10% X7R  pkg 0402  page 224 : 1 = VSENSE_PVDD11_S3_P1_R ; 2 = VSENSE_VSS_SENSE_C_P1
PC641  Q_CAP  0.22UF 25V 10% X7R  pkg C0402  page 269 : 1 = SW_P1V8_AUX_BT_R ; 2 = SW_P1V8_AUX_PH
PC643  Q_CAP  470PF 50V 10% X7R  pkg 0402  page 224 : 1 = PVDD11_S3_P1_TEMP0 ; 2 = GND
PC644  Q_CAP  10UF 6.3V 20% X6S  pkg C0402  page 224 : 1 = PVDD11_S3_P1_VCCS ; 2 = GND
PC645  Q_CAP  1UF 16V 10% X6S  pkg C0402  page 224 : 1 = PVDD11_S3_P1_VCC ; 2 = GND
PC800  Q_CAPP  470UF 2.5V 20% SPCAP  pkg SMLF  page 208 : 1 = PVDD11_S3_P0 ; 2 = GND
PC801  Q_CAPP  390UF 2.5V 20% ALUM  pkg SMLF  page 208 : 1 = PVDD11_S3_P0 ; 2 = GND
PC802  Q_CAPP  470UF 2.5V 20% SPCAP  pkg SMLF  page 225 : 1 = PVDD11_S3_P1 ; 2 = GND
PC803  Q_CAPP  390UF 2.5V 20% ALUM  pkg SMLF  page 225 : 1 = PVDD11_S3_P1 ; 2 = GND
PC819  Q_CAP  0.1UF 25V 10% X7R  pkg 0402  page 364 : 1 = P0V9_RETIMER_CPU1_VINSEN ; 2 = GND
PC850  Q_CAP  22UF 4V 20% X6S  pkg C0805  page 269 : 1 = P1V8_AUX ; 2 = GND
PC852  Q_CAP  330PF 50V 10% X7R  pkg 0402  page 270 : 1 = P1V2_AUX_FB ; 2 = P1V2_AUX
PC865  Q_CAP  22UF 4V 20% X6S  pkg C0805  page 269 : 1 = P1V8_AUX ; 2 = GND
PC866  Q_CAP  22UF 4V 20% X6S  pkg C0805  page 269 : 1 = P1V8_AUX ; 2 = GND
PC867  Q_CAP  22UF 4V 20% X6S  pkg C0805  page 269 : 1 = P1V8_AUX ; 2 = GND
PC1320  Q_CAP  2.2UF 16V 20% X7R  pkg C0603  page 141 : 1 = P12V_OCP_AVIN_PD_2 ; 2 = GND
PC1321  Q_CAP  0.068UF 16V 10% X7R  pkg 0402  page 141 : 1 = P3V3_OCP_DVDT_2 ; 2 = GND
PC1322  Q_CAP  100PF 50V 5% X7R  pkg 0402  page 141 : 1 = P3V3_OCP_GATE_PU207_2 ; 2 = GND
PC1525  Q_CAP  1UF 25V 10% X6S  pkg C0402  page 263 : 1 = HSC_VDD_R_1 ; 2 = AGND_HSC
PC1599  Q_CAP  22UF 10V 20% X6S  pkg C0805  page 190 : 1 = P3V3_AUX ; 2 = GND
PC1600  Q_CAP  22UF 10V 20% X6S  pkg C0805  page 190 : 1 = P3V3_AUX ; 2 = GND
PC1648  Q_CAP  0.1UF 25V 10% X6S  pkg C0402  page 189 : 1 = P12V_AUX ; 2 = GND
PC1649  Q_CAP  0.1UF 25V 10% X6S  pkg C0402  page 190 : 1 = P12V_AUX ; 2 = GND
PC1750  Q_CAP  33NF 25V 10% EMPTY  pkg C0402  page 266 : 1 = P12V_AUX ; 2 = P12V_HSC_GATE2
PC1751  Q_CAP  1NF 50V 10% EMPTY  pkg 0402  page 266 : 1 = P12V_HSC_GATE_RC ; 2 = P12V_HSC_GATE2
PC1789  Q_CAP  0.1UF 25V 10% X7R  pkg 0402  page 267 : 1 = P12V_AUX ; 2 = GND
PC1845  Q_CAPP  220UF 6.3V 20% ALUM  pkg SMLF  page 189 : 1 = P5V_AUX ; 2 = GND
PC1846  Q_CAP  1UF 16V 10% X6S  pkg C0402  page 189 : 1 = SW_P5V_AUX_FLT ; 2 = GND
PC1847  Q_CAP  0.22UF 25V 10% X7R  pkg C0402  page 189 : 1 = SW_P5V_AUX_BST ; 2 = SW_P5V_AUX_SW
PC1848  Q_CAP  1UF 25V 10% X6S  pkg C0402  page 189 : 1 = P5V_AUX_VCC ; 2 = GND
PC1849  Q_CAP  22UF 16V 20% X6S  pkg C0805  page 189 : 1 = SW_P5V_AUX_FLT ; 2 = GND
PC1850  Q_CAP  22UF 16V 20% X6S  pkg C0805  page 189 : 1 = SW_P5V_AUX_FLT ; 2 = GND
PC1852  Q_CAP  0.1UF 25V 10% X7R  pkg 0402  page 189 : 1 = P5V_AUX ; 2 = GND
PC1853  Q_CAP  0.1UF 25V 10% X7R  pkg 0402  page 189 : 1 = P5V_AUX_REF ; 2 = GND
PC1855  Q_CAP  22UF 10V 20% X6S  pkg C0805  page 189 : 1 = P5V_AUX ; 2 = GND
PC1856  Q_CAP  22UF 10V 20% X6S  pkg C0805  page 189 : 1 = P5V_AUX ; 2 = GND
PC1866  Q_CAPP  560UF 6.3V 20% OSCON  pkg THLF  page 190 : 1 = P3V3_AUX ; 2 = GND
PC1867  Q_CAPP  560UF 6.3V 20% OSCON  pkg THLF  page 190 : 1 = P3V3_AUX ; 2 = GND
PC1868  Q_CAP  22UF 10V 20% X6S  pkg C0805  page 190 : 1 = P3V3_AUX ; 2 = GND
PC1869  Q_CAP  0.1UF 25V 10% X7R  pkg 0402  page 190 : 1 = P3V3_AUX ; 2 = GND
PC1870  Q_CAP  0.1UF 25V 10% EMPTY  pkg 0402  page 190 : 1 = P3V3_AUX_EN ; 2 = GND
PC1877  Q_CAP  47PF 50V 5% NPO  pkg 0402  page 189 : 1 = P5V_AUX_FB ; 2 = P5V_AUX
PC1898  Q_CAP  22UF 16V 20% X6S  pkg C0805  page 189 : 1 = SW_P5V_AUX_FLT ; 2 = GND
PC2079  Q_CAP  1UF 25V 10% X6S  pkg C0402  page 134 : 1 = P12V_AUX ; 2 = GND
PC2080  Q_CAP  22UF 16V 20% X6S  pkg C0805  page 134 : 1 = P12V_OCP_SFF ; 2 = GND
PC2081  Q_CAP  10UF 16V 10% X6S  pkg C0805  page 134 : 1 = P3V3_OCP_SFF_R ; 2 = GND
PC2082  Q_CAP  10UF 16V 10% X6S  pkg C0805  page 134 : 1 = P12V_OCP_SFF ; 2 = GND
PC2085  Q_CAP  1UF 25V 10% X6S  pkg C0402  page 134 : 1 = P12V_OCP_VCC_1 ; 2 = GND
PC2086  Q_CAP  1UF 25V 10% X6S  pkg C0402  page 134 : 1 = P3V3_OCP_VCC_1 ; 2 = GND
PC2087  Q_CAP  1UF 25V 10% X6S  pkg C0402  page 134 : 1 = GND ; 2 = P12V_OCP_REG_1
PC2088  Q_CAP  0.01UF 50V 10% EMPTY  pkg C0402  page 134 : 1 = P12V_OCP_SFF ; 2 = P12V_OCP_GATE_1
PC2089  Q_CAP  6800PF 50V 10% X7R  pkg C0402  page 134 : 1 = P3V3_OCP_GATE_PU202_1 ; 2 = GND
PC2091  Q_CAP  0.1UF 25V 10% X7R  pkg 0402  page 134 : 1 = P3V3_OCP_SFF_R ; 2 = GND
PC2092  Q_CAP  0.1UF 25V 10% X7R  pkg 0402  page 134 : 1 = P12V_OCP_SFF ; 2 = GND
PC2093  Q_CAP  1UF 25V 10% X6S  pkg C0402  page 134 : 1 = GND ; 2 = P3V3_OCP_REG_1
PC2098  Q_CAP  1UF 25V 10% X6S  pkg C0402  page 140 : 1 = P12V_OCP_VCC_2 ; 2 = GND
PC2103  Q_CAP  1UF 25V 10% X6S  pkg C0402  page 262 : 1 = HSC_VDD18 ; 2 = AGND_HSC
PC2137  Q_CAP  0.1UF 25V 10% X7R  pkg 0402  page 140 : 1 = P3V3_OCP_V3_2_R ; 2 = GND
PC2139  Q_CAP  1UF 25V 10% X6S  pkg C0402  page 140 : 1 = P12V_AUX ; 2 = GND
PC2140  Q_CAP  1UF 25V 10% X6S  pkg C0402  page 140 : 1 = P3V3_AUX ; 2 = GND
PC2141  Q_CAP  22UF 16V 20% X6S  pkg C0805  page 140 : 1 = P12V_OCP_V3_2 ; 2 = GND
PC2142  Q_CAP  10UF 16V 10% X6S  pkg C0805  page 140 : 1 = P3V3_OCP_V3_2_R ; 2 = GND
PC2143  Q_CAP  10UF 16V 10% X6S  pkg C0805  page 140 : 1 = P12V_OCP_V3_2 ; 2 = GND
PC2144  Q_CAP  0.01UF 50V 10% EMPTY  pkg C0402  page 134 : 1 = P3V3_OCP_SFF_R ; 2 = P3V3_OCP_GATE_PU202_1
PC2146  Q_CAP  1UF 25V 10% X6S  pkg C0402  page 140 : 1 = GND ; 2 = P12V_OCP_REG_2
PC2147  Q_CAP  1UF 25V 10% X6S  pkg C0402  page 140 : 1 = GND ; 2 = P3V3_OCP_REG_2
PC2149  Q_CAP  0.01UF 50V 10% EMPTY  pkg C0402  page 140 : 1 = P3V3_OCP_V3_2_R ; 2 = P3V3_OCP_GATE_2
PC2150  Q_CAP  3900PF 50V 10% X7R  pkg C0402  page 140 : 1 = P12V_OCP_GATE_2 ; 2 = GND
PC2151  Q_CAP  6800PF 50V 10% X7R  pkg C0402  page 140 : 1 = P3V3_OCP_GATE_2 ; 2 = GND
PC2152  Q_CAP  0.1UF 25V 10% X7R  pkg 0402  page 140 : 1 = P12V_OCP_V3_2 ; 2 = GND
PC2153  Q_CAP  0.22UF 16V 10% X7R  pkg 0402  page 135 : 1 = P12V_OCP_TIMER_1 ; 2 = GND
PC2154  Q_CAP  1UF 25V 10% X6S  pkg C0402  page 135 : 1 = P12V_AUX ; 2 = GND
